(kicad_pcb
	(version 20260206)
	(generator "pcbnew")
	(generator_version "10.0")
	(general
		(thickness 1.6)
		(legacy_teardrops no)
	)
	(paper "A4")
	(title_block
		(title "01162023_DA0F0TEBIF0_F0T_Expander_BD_F_brd_V02_OCP.brd")
		(comment 1 "Grand Teton / footprints 4628-4634 of 9728")
	)
	(layers
		(0 "F.Cu" signal "TOP")
		(4 "In1.Cu" signal "GND")
		(6 "In2.Cu" signal "VCC")
		(8 "In3.Cu" signal "VCC1")
		(10 "In4.Cu" signal "GND1")
		(12 "In5.Cu" signal "IN1")
		(14 "In6.Cu" signal "GND2")
		(16 "In7.Cu" signal "IN2")
		(18 "In8.Cu" signal "GND3")
		(20 "In9.Cu" signal "IN3")
		(22 "In10.Cu" signal "GND4")
		(24 "In11.Cu" signal "IN4")
		(26 "In12.Cu" signal "GND5")
		(28 "In13.Cu" signal "IN5")
		(30 "In14.Cu" signal "GND6")
		(32 "In15.Cu" signal "IN6")
		(34 "In16.Cu" signal "GND7")
		(2 "B.Cu" signal "BOTTOM")
		(9 "F.Adhes" user "F.Adhesive")
		(11 "B.Adhes" user "B.Adhesive")
		(13 "F.Paste" user "Package Geometry/Pastemask Top")
		(15 "B.Paste" user "Package Geometry/Pastemask Bottom")
		(5 "F.SilkS" user "Ref Des/Silkscreen Top")
		(7 "B.SilkS" user "Ref Des/Silkscreen Bottom")
		(1 "F.Mask" user "Board Geometry/Soldermask Top")
		(3 "B.Mask" user "Board Geometry/Soldermask Bottom")
		(17 "Dwgs.User" user "User.Drawings")
		(19 "Cmts.User" user "User.Comments")
		(21 "Eco1.User" user "User.Eco1")
		(23 "Eco2.User" user "User.Eco2")
		(25 "Edge.Cuts" user "Board Geometry/Outline")
		(27 "Margin" user)
		(31 "F.CrtYd" user "Package Geometry/Place Bound Top")
		(29 "B.CrtYd" user "Package Geometry/Place Bound Bottom")
		(35 "F.Fab" user "Ref Des/Assembly Top")
		(33 "B.Fab" user "Ref Des/Assembly Bottom")
	)
	(footprint ""
		(layer "F.Cu")
		(at 171.979844 -141.9352 180)
		(property "Reference" "R112"
			(at 0 0 180)
			(layer "F.SilkS")
			(hide yes)
			(effects
				(font
					(size 1.27 1.27)
				)
			)
		)
		(property "Value" ""
			(at 0 0 180)
			(layer "F.Fab")
			(effects
				(font
					(size 1.27 1.27)
				)
			)
		)
		(duplicate_pad_numbers_are_jumpers no)
		(fp_line
			(start 0.7874 0.4064)
			(end -0.7874 0.4064)
			(stroke
				(width 0.1524)
				(type default)
			)
			(layer "F.SilkS")
		)
		(fp_line
			(start 0.7874 -0.4064)
			(end 0.7874 0.4064)
			(stroke
				(width 0.1524)
				(type default)
			)
			(layer "F.SilkS")
		)
		(fp_line
			(start -0.7874 0.4064)
			(end -0.7874 -0.4064)
			(stroke
				(width 0.1524)
				(type default)
			)
			(layer "F.SilkS")
		)
		(fp_line
			(start -0.7874 -0.4064)
			(end 0.7874 -0.4064)
			(stroke
				(width 0.1524)
				(type default)
			)
			(layer "F.SilkS")
		)
		(fp_line
			(start 0.67945 0.3048)
			(end 0.120396 0.3048)
			(stroke
				(width 0.1)
				(type default)
			)
			(layer "F.Fab")
		)
		(fp_line
			(start 0.67945 -0.3048)
			(end 0.67945 0.3048)
			(stroke
				(width 0.1)
				(type default)
			)
			(layer "F.Fab")
		)
		(fp_line
			(start 0.12065 -0.2794)
			(end 0.12065 -0.3048)
			(stroke
				(width 0.1)
				(type default)
			)
			(layer "F.Fab")
		)
		(fp_line
			(start 0.12065 -0.3048)
			(end 0.67945 -0.3048)
			(stroke
				(width 0.1)
				(type default)
			)
			(layer "F.Fab")
		)
		(fp_line
			(start 0.120396 0.3048)
			(end 0.120396 0.2794)
			(stroke
				(width 0.1)
				(type default)
			)
			(layer "F.Fab")
		)
		(fp_line
			(start 0.120396 0.2794)
			(end -0.12065 0.2794)
			(stroke
				(width 0.1)
				(type default)
			)
			(layer "F.Fab")
		)
		(fp_line
			(start -0.12065 0.3048)
			(end -0.67945 0.3048)
			(stroke
				(width 0.1)
				(type default)
			)
			(layer "F.Fab")
		)
		(fp_line
			(start -0.12065 0.2794)
			(end -0.12065 0.3048)
			(stroke
				(width 0.1)
				(type default)
			)
			(layer "F.Fab")
		)
		(fp_line
			(start -0.12065 -0.2794)
			(end 0.12065 -0.2794)
			(stroke
				(width 0.1)
				(type default)
			)
			(layer "F.Fab")
		)
		(fp_line
			(start -0.12065 -0.305054)
			(end -0.12065 -0.2794)
			(stroke
				(width 0.1)
				(type default)
			)
			(layer "F.Fab")
		)
		(fp_line
			(start -0.67945 0.3048)
			(end -0.67945 -0.305054)
			(stroke
				(width 0.1)
				(type default)
			)
			(layer "F.Fab")
		)
		(fp_line
			(start -0.67945 -0.305054)
			(end -0.12065 -0.305054)
			(stroke
				(width 0.1)
				(type default)
			)
			(layer "F.Fab")
		)
		(pad "1" smd circle
			(at -0.40005 0 180)
			(size 0 0)
			(layers "F.Cu" "F.Mask" "F.Paste")
			(net "P3V3_NIC2")
		)
		(pad "2" smd circle
			(at 0.40005 0 180)
			(size 0 0)
			(layers "F.Cu" "F.Mask" "F.Paste")
			(net "SMB_NIC2_R_SDA")
		)
	)
	(footprint ""
		(layer "F.Cu")
		(at 182.94604 -177.322988 90)
		(property "Reference" "R6672"
			(at 0 0 90)
			(layer "F.SilkS")
			(hide yes)
			(effects
				(font
					(size 1.27 1.27)
				)
			)
		)
		(property "Value" ""
			(at 0 0 90)
			(layer "F.Fab")
			(effects
				(font
					(size 1.27 1.27)
				)
			)
		)
		(duplicate_pad_numbers_are_jumpers no)
		(fp_line
			(start 0.7874 -0.4064)
			(end 0.7874 0.4064)
			(stroke
				(width 0.1524)
				(type default)
			)
			(layer "F.SilkS")
		)
		(fp_line
			(start -0.7874 -0.4064)
			(end 0.7874 -0.4064)
			(stroke
				(width 0.1524)
				(type default)
			)
			(layer "F.SilkS")
		)
		(fp_line
			(start 0.7874 0.4064)
			(end -0.7874 0.4064)
			(stroke
				(width 0.1524)
				(type default)
			)
			(layer "F.SilkS")
		)
		(fp_line
			(start -0.7874 0.4064)
			(end -0.7874 -0.4064)
			(stroke
				(width 0.1524)
				(type default)
			)
			(layer "F.SilkS")
		)
		(fp_line
			(start -0.12065 -0.305054)
			(end -0.12065 -0.2794)
			(stroke
				(width 0.1)
				(type default)
			)
			(layer "F.Fab")
		)
		(fp_line
			(start -0.67945 -0.305054)
			(end -0.12065 -0.305054)
			(stroke
				(width 0.1)
				(type default)
			)
			(layer "F.Fab")
		)
		(fp_line
			(start 0.67945 -0.3048)
			(end 0.67945 0.3048)
			(stroke
				(width 0.1)
				(type default)
			)
			(layer "F.Fab")
		)
		(fp_line
			(start 0.12065 -0.3048)
			(end 0.67945 -0.3048)
			(stroke
				(width 0.1)
				(type default)
			)
			(layer "F.Fab")
		)
		(fp_line
			(start 0.12065 -0.2794)
			(end 0.12065 -0.3048)
			(stroke
				(width 0.1)
				(type default)
			)
			(layer "F.Fab")
		)
		(fp_line
			(start -0.12065 -0.2794)
			(end 0.12065 -0.2794)
			(stroke
				(width 0.1)
				(type default)
			)
			(layer "F.Fab")
		)
		(fp_line
			(start 0.120396 0.2794)
			(end -0.12065 0.2794)
			(stroke
				(width 0.1)
				(type default)
			)
			(layer "F.Fab")
		)
		(fp_line
			(start -0.12065 0.2794)
			(end -0.12065 0.3048)
			(stroke
				(width 0.1)
				(type default)
			)
			(layer "F.Fab")
		)
		(fp_line
			(start 0.67945 0.3048)
			(end 0.120396 0.3048)
			(stroke
				(width 0.1)
				(type default)
			)
			(layer "F.Fab")
		)
		(fp_line
			(start 0.120396 0.3048)
			(end 0.120396 0.2794)
			(stroke
				(width 0.1)
				(type default)
			)
			(layer "F.Fab")
		)
		(fp_line
			(start -0.12065 0.3048)
			(end -0.67945 0.3048)
			(stroke
				(width 0.1)
				(type default)
			)
			(layer "F.Fab")
		)
		(fp_line
			(start -0.67945 0.3048)
			(end -0.67945 -0.305054)
			(stroke
				(width 0.1)
				(type default)
			)
			(layer "F.Fab")
		)
		(pad "1" smd circle
			(at -0.40005 0 90)
			(size 0 0)
			(layers "F.Cu" "F.Mask" "F.Paste")
			(net "NIC3_CLK_EN_BUF_R_N")
		)
		(pad "2" smd circle
			(at 0.40005 0 90)
			(size 0 0)
			(layers "F.Cu" "F.Mask" "F.Paste")
			(net "P3V3")
		)
	)
	(footprint ""
		(layer "F.Cu")
		(at 178.609752 -165.670484 -90)
		(property "Reference" "R2466"
			(at 0 0 270)
			(layer "F.SilkS")
			(hide yes)
			(effects
				(font
					(size 1.27 1.27)
				)
			)
		)
		(property "Value" ""
			(at 0 0 270)
			(layer "F.Fab")
			(effects
				(font
					(size 1.27 1.27)
				)
			)
		)
		(duplicate_pad_numbers_are_jumpers no)
		(fp_line
			(start -0.7874 0.4064)
			(end -0.7874 -0.4064)
			(stroke
				(width 0.1524)
				(type default)
			)
			(layer "F.SilkS")
		)
		(fp_line
			(start 0.7874 0.4064)
			(end -0.7874 0.4064)
			(stroke
				(width 0.1524)
				(type default)
			)
			(layer "F.SilkS")
		)
		(fp_line
			(start -0.7874 -0.4064)
			(end 0.7874 -0.4064)
			(stroke
				(width 0.1524)
				(type default)
			)
			(layer "F.SilkS")
		)
		(fp_line
			(start 0.7874 -0.4064)
			(end 0.7874 0.4064)
			(stroke
				(width 0.1524)
				(type default)
			)
			(layer "F.SilkS")
		)
		(fp_line
			(start -0.67945 0.3048)
			(end -0.67945 -0.305054)
			(stroke
				(width 0.1)
				(type default)
			)
			(layer "F.Fab")
		)
		(fp_line
			(start -0.12065 0.3048)
			(end -0.67945 0.3048)
			(stroke
				(width 0.1)
				(type default)
			)
			(layer "F.Fab")
		)
		(fp_line
			(start 0.120396 0.3048)
			(end 0.120396 0.2794)
			(stroke
				(width 0.1)
				(type default)
			)
			(layer "F.Fab")
		)
		(fp_line
			(start 0.67945 0.3048)
			(end 0.120396 0.3048)
			(stroke
				(width 0.1)
				(type default)
			)
			(layer "F.Fab")
		)
		(fp_line
			(start -0.12065 0.2794)
			(end -0.12065 0.3048)
			(stroke
				(width 0.1)
				(type default)
			)
			(layer "F.Fab")
		)
		(fp_line
			(start 0.120396 0.2794)
			(end -0.12065 0.2794)
			(stroke
				(width 0.1)
				(type default)
			)
			(layer "F.Fab")
		)
		(fp_line
			(start -0.12065 -0.2794)
			(end 0.12065 -0.2794)
			(stroke
				(width 0.1)
				(type default)
			)
			(layer "F.Fab")
		)
		(fp_line
			(start 0.12065 -0.2794)
			(end 0.12065 -0.3048)
			(stroke
				(width 0.1)
				(type default)
			)
			(layer "F.Fab")
		)
		(fp_line
			(start 0.12065 -0.3048)
			(end 0.67945 -0.3048)
			(stroke
				(width 0.1)
				(type default)
			)
			(layer "F.Fab")
		)
		(fp_line
			(start 0.67945 -0.3048)
			(end 0.67945 0.3048)
			(stroke
				(width 0.1)
				(type default)
			)
			(layer "F.Fab")
		)
		(fp_line
			(start -0.67945 -0.305054)
			(end -0.12065 -0.305054)
			(stroke
				(width 0.1)
				(type default)
			)
			(layer "F.Fab")
		)
		(fp_line
			(start -0.12065 -0.305054)
			(end -0.12065 -0.2794)
			(stroke
				(width 0.1)
				(type default)
			)
			(layer "F.Fab")
		)
		(pad "1" smd circle
			(at -0.40005 0 270)
			(size 0 0)
			(layers "F.Cu" "F.Mask" "F.Paste")
			(net "NIC2_PWRBRK_R_N")
		)
		(pad "2" smd circle
			(at 0.40005 0 270)
			(size 0 0)
			(layers "F.Cu" "F.Mask" "F.Paste")
			(net "NIC2_PWRBRK_N")
		)
	)
	(footprint ""
		(layer "F.Cu")
		(at 293.657782 -350.098614 90)
		(property "Reference" "C590"
			(at 0 0 90)
			(layer "F.SilkS")
			(hide yes)
			(effects
				(font
					(size 1.27 1.27)
				)
			)
		)
		(property "Value" ""
			(at 0 0 90)
			(layer "F.Fab")
			(effects
				(font
					(size 1.27 1.27)
				)
			)
		)
		(duplicate_pad_numbers_are_jumpers no)
		(fp_line
			(start 0.299974 -0.150114)
			(end 0.299974 0.150114)
			(stroke
				(width 0.1)
				(type default)
			)
			(layer "F.Fab")
		)
		(fp_line
			(start -0.299974 -0.150114)
			(end 0.299974 -0.150114)
			(stroke
				(width 0.1)
				(type default)
			)
			(layer "F.Fab")
		)
		(fp_line
			(start 0.299974 0.150114)
			(end -0.299974 0.150114)
			(stroke
				(width 0.1)
				(type default)
			)
			(layer "F.Fab")
		)
		(fp_line
			(start -0.299974 0.150114)
			(end -0.299974 -0.150114)
			(stroke
				(width 0.1)
				(type default)
			)
			(layer "F.Fab")
		)
		(pad "1" smd rect
			(at -0.2667 0 90)
			(size 0.3048 0.381)
			(layers "F.Cu" "F.Mask" "F.Paste")
			(net "P5E_PEX2_STN7_TX_DN<124>")
		)
		(pad "2" smd rect
			(at 0.2667 0 90)
			(size 0.3048 0.381)
			(layers "F.Cu" "F.Mask" "F.Paste")
			(net "P5E_PEX2_STN7_TX_C_DN<124>")
		)
	)
	(footprint ""
		(layer "F.Cu")
		(at 411.479492 -200.782682)
		(property "Reference" "Q235"
			(at -0.569214 -1.738884 0)
			(unlocked yes)
			(layer "F.SilkS")
			(effects
				(font
					(size 0.7874 0.5842)
					(thickness 0.1524)
				)
			)
		)
		(property "Value" ""
			(at 0 0 0)
			(layer "F.Fab")
			(effects
				(font
					(size 1.27 1.27)
				)
			)
		)
		(duplicate_pad_numbers_are_jumpers no)
		(fp_line
			(start -1.376172 -1.199896)
			(end -0.508 -1.199896)
			(stroke
				(width 0.1524)
				(type default)
			)
			(layer "F.SilkS")
		)
		(fp_line
			(start -1.376172 1.199896)
			(end -1.376172 -1.199896)
			(stroke
				(width 0.1524)
				(type default)
			)
			(layer "F.SilkS")
		)
		(fp_line
			(start -0.508 -1.199896)
			(end 0 -0.762)
			(stroke
				(width 0.1524)
				(type default)
			)
			(layer "F.SilkS")
		)
		(fp_line
			(start 0 -0.762)
			(end 0.508 -1.199896)
			(stroke
				(width 0.1524)
				(type default)
			)
			(layer "F.SilkS")
		)
		(fp_line
			(start 0.508 -1.199896)
			(end 1.376172 -1.199896)
			(stroke
				(width 0.1524)
				(type default)
			)
			(layer "F.SilkS")
		)
		(fp_line
			(start 1.376172 -1.199896)
			(end 1.376172 1.199896)
			(stroke
				(width 0.1524)
				(type default)
			)
			(layer "F.SilkS")
		)
		(fp_line
			(start 1.376172 1.199896)
			(end -1.376172 1.199896)
			(stroke
				(width 0.1524)
				(type default)
			)
			(layer "F.SilkS")
		)
		(fp_poly
			(pts
				(xy -1.4605 -0.7493) (xy -2.2225 -1.1303) (xy -2.2225 -0.3683)
			)
			(stroke
				(width 0)
				(type default)
			)
			(fill yes)
			(layer "F.SilkS")
		)
		(fp_line
			(start -0.674878 -1.100074)
			(end 0.674878 -1.100074)
			(stroke
				(width 0.1)
				(type default)
			)
			(layer "F.Fab")
		)
		(fp_line
			(start -0.674878 1.100074)
			(end -0.674878 -1.100074)
			(stroke
				(width 0.1)
				(type default)
			)
			(layer "F.Fab")
		)
		(fp_line
			(start 0.674878 -1.100074)
			(end 0.674878 1.100074)
			(stroke
				(width 0.1)
				(type default)
			)
			(layer "F.Fab")
		)
		(fp_line
			(start 0.674878 1.100074)
			(end -0.674878 1.100074)
			(stroke
				(width 0.1)
				(type default)
			)
			(layer "F.Fab")
		)
		(fp_poly
			(pts
				(xy -1.4605 -0.7493) (xy -2.2225 -1.1303) (xy -2.2225 -0.3683)
			)
			(stroke
				(width 0)
				(type default)
			)
			(fill yes)
			(layer "F.Fab")
		)
		(pad "1" smd rect
			(at -0.899922 -0.750062 270)
			(size 0.6096 0.6096)
			(layers "F.Cu" "F.Mask" "F.Paste")
			(net "GND")
		)
		(pad "2" smd rect
			(at -0.899922 0 270)
			(size 0.4064 0.6096)
			(layers "F.Cu" "F.Mask" "F.Paste")
			(net "FPGA_PEX1_MODE_SEL2_R")
		)
		(pad "3" smd rect
			(at -0.899922 0.750062 270)
			(size 0.6096 0.6096)
			(layers "F.Cu" "F.Mask" "F.Paste")
			(net "FPGA_PEX1_MODE_SEL2_ISO")
		)
		(pad "4" smd rect
			(at 0.899922 0.750062 270)
			(size 0.6096 0.6096)
			(layers "F.Cu" "F.Mask" "F.Paste")
			(net "GND")
		)
		(pad "5" smd rect
			(at 0.899922 0 270)
			(size 0.4064 0.6096)
			(layers "F.Cu" "F.Mask" "F.Paste")
			(net "FPGA_PEX1_MODE_SEL2_D_N")
		)
		(pad "6" smd rect
			(at 0.899922 -0.750062 270)
			(size 0.6096 0.6096)
			(layers "F.Cu" "F.Mask" "F.Paste")
			(net "FPGA_PEX1_MODE_SEL2_D_N")
		)
	)
	(footprint ""
		(layer "F.Cu")
		(at 453.827134 -366.70361)
		(property "Reference" "Q244"
			(at -0.6604 -1.793748 0)
			(unlocked yes)
			(layer "F.SilkS")
			(effects
				(font
					(size 0.7874 0.5842)
					(thickness 0.1524)
				)
			)
		)
		(property "Value" ""
			(at 0 0 0)
			(layer "F.Fab")
			(effects
				(font
					(size 1.27 1.27)
				)
			)
		)
		(duplicate_pad_numbers_are_jumpers no)
		(fp_line
			(start -1.376172 -1.199896)
			(end -0.508 -1.199896)
			(stroke
				(width 0.1524)
				(type default)
			)
			(layer "F.SilkS")
		)
		(fp_line
			(start -1.376172 1.199896)
			(end -1.376172 -1.199896)
			(stroke
				(width 0.1524)
				(type default)
			)
			(layer "F.SilkS")
		)
		(fp_line
			(start -0.508 -1.199896)
			(end 0 -0.762)
			(stroke
				(width 0.1524)
				(type default)
			)
			(layer "F.SilkS")
		)
		(fp_line
			(start 0 -0.762)
			(end 0.508 -1.199896)
			(stroke
				(width 0.1524)
				(type default)
			)
			(layer "F.SilkS")
		)
		(fp_line
			(start 0.508 -1.199896)
			(end 1.376172 -1.199896)
			(stroke
				(width 0.1524)
				(type default)
			)
			(layer "F.SilkS")
		)
		(fp_line
			(start 1.376172 -1.199896)
			(end 1.376172 1.199896)
			(stroke
				(width 0.1524)
				(type default)
			)
			(layer "F.SilkS")
		)
		(fp_line
			(start 1.376172 1.199896)
			(end -1.376172 1.199896)
			(stroke
				(width 0.1524)
				(type default)
			)
			(layer "F.SilkS")
		)
		(fp_poly
			(pts
				(xy -1.4605 -0.7493) (xy -2.2225 -1.1303) (xy -2.2225 -0.3683)
			)
			(stroke
				(width 0)
				(type default)
			)
			(fill yes)
			(layer "F.SilkS")
		)
		(fp_line
			(start -0.674878 -1.100074)
			(end 0.674878 -1.100074)
			(stroke
				(width 0.1)
				(type default)
			)
			(layer "F.Fab")
		)
		(fp_line
			(start -0.674878 1.100074)
			(end -0.674878 -1.100074)
			(stroke
				(width 0.1)
				(type default)
			)
			(layer "F.Fab")
		)
		(fp_line
			(start 0.674878 -1.100074)
			(end 0.674878 1.100074)
			(stroke
				(width 0.1)
				(type default)
			)
			(layer "F.Fab")
		)
		(fp_line
			(start 0.674878 1.100074)
			(end -0.674878 1.100074)
			(stroke
				(width 0.1)
				(type default)
			)
			(layer "F.Fab")
		)
		(fp_poly
			(pts
				(xy -1.4605 -0.7493) (xy -2.2225 -1.1303) (xy -2.2225 -0.3683)
			)
			(stroke
				(width 0)
				(type default)
			)
			(fill yes)
			(layer "F.Fab")
		)
		(pad "1" smd rect
			(at -0.899922 -0.750062 270)
			(size 0.6096 0.6096)
			(layers "F.Cu" "F.Mask" "F.Paste")
			(net "GND")
		)
		(pad "2" smd rect
			(at -0.899922 0 270)
			(size 0.4064 0.6096)
			(layers "F.Cu" "F.Mask" "F.Paste")
			(net "GPU_3V3IO_RSVD1")
		)
		(pad "3" smd rect
			(at -0.899922 0.750062 270)
			(size 0.6096 0.6096)
			(layers "F.Cu" "F.Mask" "F.Paste")
			(net "GPU_3V3IO_RSVD1_ISO")
		)
		(pad "4" smd rect
			(at 0.899922 0.750062 270)
			(size 0.6096 0.6096)
			(layers "F.Cu" "F.Mask" "F.Paste")
			(net "GND")
		)
		(pad "5" smd rect
			(at 0.899922 0 270)
			(size 0.4064 0.6096)
			(layers "F.Cu" "F.Mask" "F.Paste")
			(net "GPU_3V3IO_RSVD1_N")
		)
		(pad "6" smd rect
			(at 0.899922 -0.750062 270)
			(size 0.6096 0.6096)
			(layers "F.Cu" "F.Mask" "F.Paste")
			(net "GPU_3V3IO_RSVD1_N")
		)
	)
	(footprint ""
		(layer "F.Cu")
		(at 278.634444 -34.546286 180)
		(property "Reference" "C495"
			(at 0 0 180)
			(layer "F.SilkS")
			(hide yes)
			(effects
				(font
					(size 1.27 1.27)
				)
			)
		)
		(property "Value" ""
			(at 0 0 180)
			(layer "F.Fab")
			(effects
				(font
					(size 1.27 1.27)
				)
			)
		)
		(duplicate_pad_numbers_are_jumpers no)
		(fp_line
			(start 0.299974 0.150114)
			(end -0.299974 0.150114)
			(stroke
				(width 0.1)
				(type default)
			)
			(layer "F.Fab")
		)
		(fp_line
			(start 0.299974 -0.150114)
			(end 0.299974 0.150114)
			(stroke
				(width 0.1)
				(type default)
			)
			(layer "F.Fab")
		)
		(fp_line
			(start -0.299974 0.150114)
			(end -0.299974 -0.150114)
			(stroke
				(width 0.1)
				(type default)
			)
			(layer "F.Fab")
		)
		(fp_line
			(start -0.299974 -0.150114)
			(end 0.299974 -0.150114)
			(stroke
				(width 0.1)
				(type default)
			)
			(layer "F.Fab")
		)
		(pad "1" smd rect
			(at -0.2667 0 180)
			(size 0.3048 0.381)
			(layers "F.Cu" "F.Mask" "F.Paste")
			(net "P5E_PEX2_STN2_TX_DP<43>")
		)
		(pad "2" smd rect
			(at 0.2667 0 180)
			(size 0.3048 0.381)
			(layers "F.Cu" "F.Mask" "F.Paste")
			(net "P5E_PEX2_STN2_TX_C_DP<43>")
		)
	)
)
